# T6G (Grand Teton) — schematic netlist excerpt (pin names and nets, part order shuffled) for the footprints in the layout excerpt that follows; sources: Cadence DE-HDL packaged netlist, KiCad conversion of 04192023_DAF0TMB3IC0_F0TG_MB_C_brd_V02_OCP.brd

PR4  Q_RES  10K 1% CHIP  pkg 0402LF  page 210 : A = PVDDCR_CPU0_P1_VMON ; B = GND
C6568  Q_CAP_DIFFBUS  DIFF BUS_0.22UF 6.3V 20% X6S  pkg C0201  page 297 : \1\ = P5E_CPU0_P2_TX_BUF_C_DN<1> ; \2\ = P5E_CPU0_P2_TX_BUF_DN<1>
PC154  Q_CAP  560PF 50V 10% EMPTY  pkg C0402  page 203 : A = SW_PVDDCR_CPU1_P0_SW6 ; B = SW_PVDDCR_CPU1_P0_SW6_RC

(kicad_pcb
	(version 20260206)
	(generator "pcbnew")
	(generator_version "10.0")
	(general
		(thickness 1.6)
		(legacy_teardrops no)
	)
	(paper "A4")
	(title_block
		(title "04192023_DAF0TMB3IC0_F0TG_MB_C_brd_V02_OCP.brd")
		(comment 1 "Grand Teton / footprints 1889-1891 of 8354")
	)
	(layers
		(0 "F.Cu" signal "TOP")
		(4 "In1.Cu" signal "GND")
		(6 "In2.Cu" signal "IN1")
		(8 "In3.Cu" signal "GND1")
		(10 "In4.Cu" signal "IN2")
		(12 "In5.Cu" signal "GND2")
		(14 "In6.Cu" signal "IN3")
		(16 "In7.Cu" signal "GND3")
		(18 "In8.Cu" signal "VCC")
		(20 "In9.Cu" signal "VCC1")
		(22 "In10.Cu" signal "GND4")
		(24 "In11.Cu" signal "IN4")
		(26 "In12.Cu" signal "GND5")
		(28 "In13.Cu" signal "IN5")
		(30 "In14.Cu" signal "GND6")
		(32 "In15.Cu" signal "IN6")
		(34 "In16.Cu" signal "GND7")
		(2 "B.Cu" signal "BOTTOM")
		(9 "F.Adhes" user "F.Adhesive")
		(11 "B.Adhes" user "B.Adhesive")
		(13 "F.Paste" user "Package Geometry/Pastemask Top")
		(15 "B.Paste" user "Package Geometry/Pastemask Bottom")
		(5 "F.SilkS" user "Ref Des/Silkscreen Top")
		(7 "B.SilkS" user "Ref Des/Silkscreen Bottom")
		(1 "F.Mask" user "Board Geometry/Soldermask Top")
		(3 "B.Mask" user "Board Geometry/Soldermask Bottom")
		(17 "Dwgs.User" user "User.Drawings")
		(19 "Cmts.User" user "User.Comments")
		(21 "Eco1.User" user "User.Eco1")
		(23 "Eco2.User" user "User.Eco2")
		(25 "Edge.Cuts" user "Board Geometry/Outline")
		(27 "Margin" user)
		(31 "F.CrtYd" user "Package Geometry/Place Bound Top")
		(29 "B.CrtYd" user "Package Geometry/Place Bound Bottom")
		(35 "F.Fab" user "Ref Des/Assembly Top")
		(33 "B.Fab" user "Ref Des/Assembly Bottom")
	)
	(footprint ""
		(layer "F.Cu")
		(at 347.972126 -336.930238 180)
		(property "Reference" "PC154"
			(at 0 0 180)
			(layer "F.SilkS")
			(hide yes)
			(effects
				(font
					(size 1.27 1.27)
				)
			)
		)
		(property "Value" ""
			(at 0 0 180)
			(layer "F.Fab")
			(effects
				(font
					(size 1.27 1.27)
				)
			)
		)
		(duplicate_pad_numbers_are_jumpers no)
		(fp_line
			(start 0.7874 0.4064)
			(end -0.7874 0.4064)
			(stroke
				(width 0.1524)
				(type default)
			)
			(layer "F.SilkS")
		)
		(fp_line
			(start 0.7874 -0.4064)
			(end 0.7874 0.4064)
			(stroke
				(width 0.1524)
				(type default)
			)
			(layer "F.SilkS")
		)
		(fp_line
			(start -0.7874 0.4064)
			(end -0.7874 -0.4064)
			(stroke
				(width 0.1524)
				(type default)
			)
			(layer "F.SilkS")
		)
		(fp_line
			(start -0.7874 -0.4064)
			(end 0.7874 -0.4064)
			(stroke
				(width 0.1524)
				(type default)
			)
			(layer "F.SilkS")
		)
		(fp_line
			(start 0.67945 0.3048)
			(end 0.120396 0.3048)
			(stroke
				(width 0.1)
				(type default)
			)
			(layer "F.Fab")
		)
		(fp_line
			(start 0.67945 -0.3048)
			(end 0.67945 0.3048)
			(stroke
				(width 0.1)
				(type default)
			)
			(layer "F.Fab")
		)
		(fp_line
			(start 0.12065 -0.2794)
			(end 0.12065 -0.3048)
			(stroke
				(width 0.1)
				(type default)
			)
			(layer "F.Fab")
		)
		(fp_line
			(start 0.12065 -0.3048)
			(end 0.67945 -0.3048)
			(stroke
				(width 0.1)
				(type default)
			)
			(layer "F.Fab")
		)
		(fp_line
			(start 0.120396 0.3048)
			(end 0.120396 0.2794)
			(stroke
				(width 0.1)
				(type default)
			)
			(layer "F.Fab")
		)
		(fp_line
			(start 0.120396 0.2794)
			(end -0.12065 0.2794)
			(stroke
				(width 0.1)
				(type default)
			)
			(layer "F.Fab")
		)
		(fp_line
			(start -0.12065 0.3048)
			(end -0.67945 0.3048)
			(stroke
				(width 0.1)
				(type default)
			)
			(layer "F.Fab")
		)
		(fp_line
			(start -0.12065 0.2794)
			(end -0.12065 0.3048)
			(stroke
				(width 0.1)
				(type default)
			)
			(layer "F.Fab")
		)
		(fp_line
			(start -0.12065 -0.2794)
			(end 0.12065 -0.2794)
			(stroke
				(width 0.1)
				(type default)
			)
			(layer "F.Fab")
		)
		(fp_line
			(start -0.12065 -0.305054)
			(end -0.12065 -0.2794)
			(stroke
				(width 0.1)
				(type default)
			)
			(layer "F.Fab")
		)
		(fp_line
			(start -0.67945 0.3048)
			(end -0.67945 -0.305054)
			(stroke
				(width 0.1)
				(type default)
			)
			(layer "F.Fab")
		)
		(fp_line
			(start -0.67945 -0.305054)
			(end -0.12065 -0.305054)
			(stroke
				(width 0.1)
				(type default)
			)
			(layer "F.Fab")
		)
		(pad "1" smd circle
			(at -0.40005 0 180)
			(size 0 0)
			(layers "F.Cu" "F.Mask" "F.Paste")
			(net "SW_PVDDCR_CPU1_P0_SW6")
		)
		(pad "2" smd circle
			(at 0.40005 0 180)
			(size 0 0)
			(layers "F.Cu" "F.Mask" "F.Paste")
			(net "SW_PVDDCR_CPU1_P0_SW6_RC")
		)
	)
	(footprint ""
		(layer "F.Cu")
		(at 98.845878 -143.74241 180)
		(property "Reference" "PR4"
			(at 0 0 180)
			(layer "F.SilkS")
			(hide yes)
			(effects
				(font
					(size 1.27 1.27)
				)
			)
		)
		(property "Value" ""
			(at 0 0 180)
			(layer "F.Fab")
			(effects
				(font
					(size 1.27 1.27)
				)
			)
		)
		(duplicate_pad_numbers_are_jumpers no)
		(fp_line
			(start 0.7874 0.4064)
			(end -0.7874 0.4064)
			(stroke
				(width 0.1524)
				(type default)
			)
			(layer "F.SilkS")
		)
		(fp_line
			(start 0.7874 -0.4064)
			(end 0.7874 0.4064)
			(stroke
				(width 0.1524)
				(type default)
			)
			(layer "F.SilkS")
		)
		(fp_line
			(start -0.7874 0.4064)
			(end -0.7874 -0.4064)
			(stroke
				(width 0.1524)
				(type default)
			)
			(layer "F.SilkS")
		)
		(fp_line
			(start -0.7874 -0.4064)
			(end 0.7874 -0.4064)
			(stroke
				(width 0.1524)
				(type default)
			)
			(layer "F.SilkS")
		)
		(fp_line
			(start 0.67945 0.3048)
			(end 0.120396 0.3048)
			(stroke
				(width 0.1)
				(type default)
			)
			(layer "F.Fab")
		)
		(fp_line
			(start 0.67945 -0.3048)
			(end 0.67945 0.3048)
			(stroke
				(width 0.1)
				(type default)
			)
			(layer "F.Fab")
		)
		(fp_line
			(start 0.12065 -0.2794)
			(end 0.12065 -0.3048)
			(stroke
				(width 0.1)
				(type default)
			)
			(layer "F.Fab")
		)
		(fp_line
			(start 0.12065 -0.3048)
			(end 0.67945 -0.3048)
			(stroke
				(width 0.1)
				(type default)
			)
			(layer "F.Fab")
		)
		(fp_line
			(start 0.120396 0.3048)
			(end 0.120396 0.2794)
			(stroke
				(width 0.1)
				(type default)
			)
			(layer "F.Fab")
		)
		(fp_line
			(start 0.120396 0.2794)
			(end -0.12065 0.2794)
			(stroke
				(width 0.1)
				(type default)
			)
			(layer "F.Fab")
		)
		(fp_line
			(start -0.12065 0.3048)
			(end -0.67945 0.3048)
			(stroke
				(width 0.1)
				(type default)
			)
			(layer "F.Fab")
		)
		(fp_line
			(start -0.12065 0.2794)
			(end -0.12065 0.3048)
			(stroke
				(width 0.1)
				(type default)
			)
			(layer "F.Fab")
		)
		(fp_line
			(start -0.12065 -0.2794)
			(end 0.12065 -0.2794)
			(stroke
				(width 0.1)
				(type default)
			)
			(layer "F.Fab")
		)
		(fp_line
			(start -0.12065 -0.305054)
			(end -0.12065 -0.2794)
			(stroke
				(width 0.1)
				(type default)
			)
			(layer "F.Fab")
		)
		(fp_line
			(start -0.67945 0.3048)
			(end -0.67945 -0.305054)
			(stroke
				(width 0.1)
				(type default)
			)
			(layer "F.Fab")
		)
		(fp_line
			(start -0.67945 -0.305054)
			(end -0.12065 -0.305054)
			(stroke
				(width 0.1)
				(type default)
			)
			(layer "F.Fab")
		)
		(pad "1" smd circle
			(at -0.40005 0 180)
			(size 0 0)
			(layers "F.Cu" "F.Mask" "F.Paste")
			(net "PVDDCR_CPU0_P1_VMON")
		)
		(pad "2" smd circle
			(at 0.40005 0 180)
			(size 0 0)
			(layers "F.Cu" "F.Mask" "F.Paste")
			(net "GND")
		)
	)
	(footprint ""
		(layer "F.Cu")
		(at 373.931942 -416.899344 -90)
		(property "Reference" "C6568"
			(at 0 0 270)
			(layer "F.SilkS")
			(hide yes)
			(effects
				(font
					(size 1.27 1.27)
				)
			)
		)
		(property "Value" ""
			(at 0 0 270)
			(layer "F.Fab")
			(effects
				(font
					(size 1.27 1.27)
				)
			)
		)
		(duplicate_pad_numbers_are_jumpers no)
		(fp_line
			(start -0.299974 0.150114)
			(end -0.299974 -0.150114)
			(stroke
				(width 0.1)
				(type default)
			)
			(layer "F.Fab")
		)
		(fp_line
			(start 0.299974 0.150114)
			(end -0.299974 0.150114)
			(stroke
				(width 0.1)
				(type default)
			)
			(layer "F.Fab")
		)
		(fp_line
			(start -0.299974 -0.150114)
			(end 0.299974 -0.150114)
			(stroke
				(width 0.1)
				(type default)
			)
			(layer "F.Fab")
		)
		(fp_line
			(start 0.299974 -0.150114)
			(end 0.299974 0.150114)
			(stroke
				(width 0.1)
				(type default)
			)
			(layer "F.Fab")
		)
		(pad "1" smd rect
			(at -0.2667 0 270)
			(size 0.3048 0.381)
			(layers "F.Cu" "F.Mask" "F.Paste")
			(net "P5E_CPU0_P2_TX_BUF_C_DN<1>")
		)
		(pad "2" smd rect
			(at 0.2667 0 270)
			(size 0.3048 0.381)
			(layers "F.Cu" "F.Mask" "F.Paste")
			(net "P5E_CPU0_P2_TX_BUF_DN<1>")
		)
	)
)
